# T6G (Grand Teton) — schematic netlist excerpt (pin names and nets, part order shuffled) for the footprints in the layout excerpt that follows; sources: Cadence DE-HDL packaged netlist, KiCad conversion of 04192023_DAF0TMB3IC0_F0TG_MB_C_brd_V02_OCP.brd

R1421  Q_RES  4.7K 5% CHIP  pkg 0201LF  page 342 : A = CLKREQ_RT_CPU1_P2_N ; B = GND
R3441  Q_RES  0 5% CHIP  pkg 0402LF  page 123 : A = GPU_BASE_ID1 ; B = GND
R661  Q_RES  0 5% CHIP  pkg 0402LF  page 364 : A = PWRGD_P0V9_RETIMER_CPU1 ; B = PWRGD_P0V9_RETIMER_CPU1_R

(kicad_pcb
	(version 20260206)
	(generator "pcbnew")
	(generator_version "10.0")
	(general
		(thickness 1.6)
		(legacy_teardrops no)
	)
	(paper "A4")
	(title_block
		(title "04192023_DAF0TMB3IC0_F0TG_MB_C_brd_V02_OCP.brd")
		(comment 1 "Grand Teton / footprints 2961-2963 of 8354")
	)
	(layers
		(0 "F.Cu" signal "TOP")
		(4 "In1.Cu" signal "GND")
		(6 "In2.Cu" signal "IN1")
		(8 "In3.Cu" signal "GND1")
		(10 "In4.Cu" signal "IN2")
		(12 "In5.Cu" signal "GND2")
		(14 "In6.Cu" signal "IN3")
		(16 "In7.Cu" signal "GND3")
		(18 "In8.Cu" signal "VCC")
		(20 "In9.Cu" signal "VCC1")
		(22 "In10.Cu" signal "GND4")
		(24 "In11.Cu" signal "IN4")
		(26 "In12.Cu" signal "GND5")
		(28 "In13.Cu" signal "IN5")
		(30 "In14.Cu" signal "GND6")
		(32 "In15.Cu" signal "IN6")
		(34 "In16.Cu" signal "GND7")
		(2 "B.Cu" signal "BOTTOM")
		(9 "F.Adhes" user "F.Adhesive")
		(11 "B.Adhes" user "B.Adhesive")
		(13 "F.Paste" user "Package Geometry/Pastemask Top")
		(15 "B.Paste" user "Package Geometry/Pastemask Bottom")
		(5 "F.SilkS" user "Ref Des/Silkscreen Top")
		(7 "B.SilkS" user "Ref Des/Silkscreen Bottom")
		(1 "F.Mask" user "Board Geometry/Soldermask Top")
		(3 "B.Mask" user "Board Geometry/Soldermask Bottom")
		(17 "Dwgs.User" user "User.Drawings")
		(19 "Cmts.User" user "User.Comments")
		(21 "Eco1.User" user "User.Eco1")
		(23 "Eco2.User" user "User.Eco2")
		(25 "Edge.Cuts" user "Board Geometry/Outline")
		(27 "Margin" user)
		(31 "F.CrtYd" user "Package Geometry/Place Bound Top")
		(29 "B.CrtYd" user "Package Geometry/Place Bound Bottom")
		(35 "F.Fab" user "Ref Des/Assembly Top")
		(33 "B.Fab" user "Ref Des/Assembly Bottom")
	)
	(footprint ""
		(layer "F.Cu")
		(at 18.45564 -404.341584 90)
		(property "Reference" "R661"
			(at 0 0 90)
			(layer "F.SilkS")
			(hide yes)
			(effects
				(font
					(size 1.27 1.27)
				)
			)
		)
		(property "Value" ""
			(at 0 0 90)
			(layer "F.Fab")
			(effects
				(font
					(size 1.27 1.27)
				)
			)
		)
		(duplicate_pad_numbers_are_jumpers no)
		(fp_line
			(start 0.7874 -0.4064)
			(end 0.7874 0.4064)
			(stroke
				(width 0.1524)
				(type default)
			)
			(layer "F.SilkS")
		)
		(fp_line
			(start -0.7874 -0.4064)
			(end 0.7874 -0.4064)
			(stroke
				(width 0.1524)
				(type default)
			)
			(layer "F.SilkS")
		)
		(fp_line
			(start 0.7874 0.4064)
			(end -0.7874 0.4064)
			(stroke
				(width 0.1524)
				(type default)
			)
			(layer "F.SilkS")
		)
		(fp_line
			(start -0.7874 0.4064)
			(end -0.7874 -0.4064)
			(stroke
				(width 0.1524)
				(type default)
			)
			(layer "F.SilkS")
		)
		(fp_line
			(start -0.12065 -0.305054)
			(end -0.12065 -0.2794)
			(stroke
				(width 0.1)
				(type default)
			)
			(layer "F.Fab")
		)
		(fp_line
			(start -0.67945 -0.305054)
			(end -0.12065 -0.305054)
			(stroke
				(width 0.1)
				(type default)
			)
			(layer "F.Fab")
		)
		(fp_line
			(start 0.67945 -0.3048)
			(end 0.67945 0.3048)
			(stroke
				(width 0.1)
				(type default)
			)
			(layer "F.Fab")
		)
		(fp_line
			(start 0.12065 -0.3048)
			(end 0.67945 -0.3048)
			(stroke
				(width 0.1)
				(type default)
			)
			(layer "F.Fab")
		)
		(fp_line
			(start 0.12065 -0.2794)
			(end 0.12065 -0.3048)
			(stroke
				(width 0.1)
				(type default)
			)
			(layer "F.Fab")
		)
		(fp_line
			(start -0.12065 -0.2794)
			(end 0.12065 -0.2794)
			(stroke
				(width 0.1)
				(type default)
			)
			(layer "F.Fab")
		)
		(fp_line
			(start 0.120396 0.2794)
			(end -0.12065 0.2794)
			(stroke
				(width 0.1)
				(type default)
			)
			(layer "F.Fab")
		)
		(fp_line
			(start -0.12065 0.2794)
			(end -0.12065 0.3048)
			(stroke
				(width 0.1)
				(type default)
			)
			(layer "F.Fab")
		)
		(fp_line
			(start 0.67945 0.3048)
			(end 0.120396 0.3048)
			(stroke
				(width 0.1)
				(type default)
			)
			(layer "F.Fab")
		)
		(fp_line
			(start 0.120396 0.3048)
			(end 0.120396 0.2794)
			(stroke
				(width 0.1)
				(type default)
			)
			(layer "F.Fab")
		)
		(fp_line
			(start -0.12065 0.3048)
			(end -0.67945 0.3048)
			(stroke
				(width 0.1)
				(type default)
			)
			(layer "F.Fab")
		)
		(fp_line
			(start -0.67945 0.3048)
			(end -0.67945 -0.305054)
			(stroke
				(width 0.1)
				(type default)
			)
			(layer "F.Fab")
		)
		(pad "1" smd circle
			(at -0.40005 0 90)
			(size 0 0)
			(layers "F.Cu" "F.Mask" "F.Paste")
			(net "PWRGD_P0V9_RETIMER_CPU1")
		)
		(pad "2" smd circle
			(at 0.40005 0 90)
			(size 0 0)
			(layers "F.Cu" "F.Mask" "F.Paste")
			(net "PWRGD_P0V9_RETIMER_CPU1_R")
		)
	)
	(footprint ""
		(layer "F.Cu")
		(at 187.316872 -428.930562 90)
		(property "Reference" "R3441"
			(at 0 0 90)
			(layer "F.SilkS")
			(hide yes)
			(effects
				(font
					(size 1.27 1.27)
				)
			)
		)
		(property "Value" ""
			(at 0 0 90)
			(layer "F.Fab")
			(effects
				(font
					(size 1.27 1.27)
				)
			)
		)
		(duplicate_pad_numbers_are_jumpers no)
		(fp_line
			(start 0.7874 -0.4064)
			(end 0.7874 0.4064)
			(stroke
				(width 0.1524)
				(type default)
			)
			(layer "F.SilkS")
		)
		(fp_line
			(start -0.7874 -0.4064)
			(end 0.7874 -0.4064)
			(stroke
				(width 0.1524)
				(type default)
			)
			(layer "F.SilkS")
		)
		(fp_line
			(start 0.7874 0.4064)
			(end -0.7874 0.4064)
			(stroke
				(width 0.1524)
				(type default)
			)
			(layer "F.SilkS")
		)
		(fp_line
			(start -0.7874 0.4064)
			(end -0.7874 -0.4064)
			(stroke
				(width 0.1524)
				(type default)
			)
			(layer "F.SilkS")
		)
		(fp_line
			(start -0.12065 -0.305054)
			(end -0.12065 -0.2794)
			(stroke
				(width 0.1)
				(type default)
			)
			(layer "F.Fab")
		)
		(fp_line
			(start -0.67945 -0.305054)
			(end -0.12065 -0.305054)
			(stroke
				(width 0.1)
				(type default)
			)
			(layer "F.Fab")
		)
		(fp_line
			(start 0.67945 -0.3048)
			(end 0.67945 0.3048)
			(stroke
				(width 0.1)
				(type default)
			)
			(layer "F.Fab")
		)
		(fp_line
			(start 0.12065 -0.3048)
			(end 0.67945 -0.3048)
			(stroke
				(width 0.1)
				(type default)
			)
			(layer "F.Fab")
		)
		(fp_line
			(start 0.12065 -0.2794)
			(end 0.12065 -0.3048)
			(stroke
				(width 0.1)
				(type default)
			)
			(layer "F.Fab")
		)
		(fp_line
			(start -0.12065 -0.2794)
			(end 0.12065 -0.2794)
			(stroke
				(width 0.1)
				(type default)
			)
			(layer "F.Fab")
		)
		(fp_line
			(start 0.120396 0.2794)
			(end -0.12065 0.2794)
			(stroke
				(width 0.1)
				(type default)
			)
			(layer "F.Fab")
		)
		(fp_line
			(start -0.12065 0.2794)
			(end -0.12065 0.3048)
			(stroke
				(width 0.1)
				(type default)
			)
			(layer "F.Fab")
		)
		(fp_line
			(start 0.67945 0.3048)
			(end 0.120396 0.3048)
			(stroke
				(width 0.1)
				(type default)
			)
			(layer "F.Fab")
		)
		(fp_line
			(start 0.120396 0.3048)
			(end 0.120396 0.2794)
			(stroke
				(width 0.1)
				(type default)
			)
			(layer "F.Fab")
		)
		(fp_line
			(start -0.12065 0.3048)
			(end -0.67945 0.3048)
			(stroke
				(width 0.1)
				(type default)
			)
			(layer "F.Fab")
		)
		(fp_line
			(start -0.67945 0.3048)
			(end -0.67945 -0.305054)
			(stroke
				(width 0.1)
				(type default)
			)
			(layer "F.Fab")
		)
		(pad "1" smd circle
			(at -0.40005 0 90)
			(size 0 0)
			(layers "F.Cu" "F.Mask" "F.Paste")
			(net "GPU_BASE_ID1")
		)
		(pad "2" smd circle
			(at 0.40005 0 90)
			(size 0 0)
			(layers "F.Cu" "F.Mask" "F.Paste")
			(net "GND")
		)
	)
	(footprint ""
		(layer "F.Cu")
		(at 169.724324 -382.038606 -90)
		(property "Reference" "R1421"
			(at 0 0 270)
			(layer "F.SilkS")
			(hide yes)
			(effects
				(font
					(size 1.27 1.27)
				)
			)
		)
		(property "Value" ""
			(at 0 0 270)
			(layer "F.Fab")
			(effects
				(font
					(size 1.27 1.27)
				)
			)
		)
		(duplicate_pad_numbers_are_jumpers no)
		(fp_line
			(start -0.32512 0.175006)
			(end -0.32512 -0.175006)
			(stroke
				(width 0.1)
				(type default)
			)
			(layer "F.Fab")
		)
		(fp_line
			(start 0.32512 0.175006)
			(end -0.32512 0.175006)
			(stroke
				(width 0.1)
				(type default)
			)
			(layer "F.Fab")
		)
		(fp_line
			(start -0.32512 -0.175006)
			(end 0.32512 -0.175006)
			(stroke
				(width 0.1)
				(type default)
			)
			(layer "F.Fab")
		)
		(fp_line
			(start 0.32512 -0.175006)
			(end 0.32512 0.175006)
			(stroke
				(width 0.1)
				(type default)
			)
			(layer "F.Fab")
		)
		(pad "1" smd rect
			(at -0.2667 0 270)
			(size 0.3048 0.381)
			(layers "F.Cu" "F.Mask" "F.Paste")
			(net "CLKREQ_RT_CPU1_P2_N")
		)
		(pad "2" smd rect
			(at 0.2667 0 90)
			(size 0.3048 0.381)
			(layers "F.Cu" "F.Mask" "F.Paste")
			(net "GND")
		)
	)
)
